# T6G (Grand Teton) — schematic parts with pin connectivity, parts 8081–8081 of 8303; source: Cadence DE-HDL packaged netlist (pstxprt.dat, pstxnet.dat, pstchip.dat)

U25  GENOA_SP5  SOCKET6096_13568-001 IO  pkg SOCKET6096_93-4X120-45XA  page 10  (pins 2017-2352 of 6096)
  BK65  MFB_CA5  OUT  = M_F_CPU0_SB_CA<5>
  BK66  VSS_BK66  POWER  = GND
  BK67  MFB_CA6  OUT  = M_F_CPU0_SB_CA<6>
  BK68  VSS_BK68  POWER  = GND
  BK69  MEB_CA5  OUT  = M_E_CPU0_SB_CA<5>
  BK70  MEB_CA6  OUT  = M_E_CPU0_SB_CA<6>
  BK71  VSS_BK71  POWER  = GND
  BK72  MAB_CA5  OUT  = M_A_CPU0_SB_CA<5>
  BK73  VSS_BK73  POWER  = GND
  BK74  MAB_CA6  OUT  = M_A_CPU0_SB_CA<6>
  BL1  VSS_BL1  POWER  = GND
  BL2  MGB1_CS_L0  OUT  = NC
  BL3  MGB_PAR  OUT  = M_G_CPU0_SB_PAR
  BL4  VSS_BL4  POWER  = GND
  BL5  MKB1_CS_L0  OUT  = NC
  BL6  VSS_BL6  POWER  = GND
  BL7  MKB_PAR  OUT  = M_K_CPU0_SB_PAR
  BL8  VSS_BL8  POWER  = GND
  BL9  MLB1_CS_L0  OUT  = NC
  BL10  MLB_PAR  OUT  = M_L_CPU0_SB_PAR
  BL11  VSS_BL11  POWER  = GND
  BL12  MHB1_CS_L0  OUT  = NC
  BL13  VSS_BL13  POWER  = GND
  BL14  MHB_PAR  OUT  = M_H_CPU0_SB_PAR
  BL15  VSS_BL15  POWER  = GND
  BL16  MJB1_CS_L0  OUT  = NC
  BL17  MJB_PAR  OUT  = M_J_CPU0_SB_PAR
  BL18  VSS_BL18  POWER  = GND
  BL19  MIB1_CS_L0  OUT  = NC
  BL20  VSS_BL20  POWER  = GND
  BL21  MIB_PAR  OUT  = M_I_CPU0_SB_PAR
  BL22  VSS_BL22  POWER  = GND
  BL23  VDD_11_S3_BL23  POWER  = PVDD11_S3_P0
  BL24  VSS_BL24  POWER  = GND
  BL25  VDD_11_S3_BL25  POWER  = PVDD11_S3_P0
  BL26  VSS_BL26  POWER  = GND
  BL27  VDD_11_S3_BL27  POWER  = PVDD11_S3_P0
  BL28  VSS_BL28  POWER  = GND
  BL48  VDD_11_S3_BL48  POWER  = PVDD11_S3_P0
  BL49  VSS_BL49  POWER  = GND
  BL50  VDDIO_BL50  POWER  = PVDDIO_P0
  BL51  VSS_BL51  POWER  = GND
  BL52  VDDIO_BL52  POWER  = PVDDIO_P0
  BL53  VSS_BL53  POWER  = GND
  BL54  VDDIO_BL54  POWER  = PVDDIO_P0
  BL55  MCB1_CS_L0  OUT  = NC
  BL56  VSS_BL56  POWER  = GND
  BL57  MCB_PAR  OUT  = M_C_CPU0_SB_PAR
  BL58  VSS_BL58  POWER  = GND
  BL59  MDB1_CS_L0  OUT  = NC
  BL60  MDB_PAR  OUT  = M_D_CPU0_SB_PAR
  BL61  VSS_BL61  POWER  = GND
  BL62  MBB1_CS_L0  OUT  = NC
  BL63  VSS_BL63  POWER  = GND
  BL64  MBB_PAR  OUT  = M_B_CPU0_SB_PAR
  BL65  VSS_BL65  POWER  = GND
  BL66  MFB1_CS_L0  OUT  = NC
  BL67  MFB_PAR  OUT  = M_F_CPU0_SB_PAR
  BL68  VSS_BL68  POWER  = GND
  BL69  MEB1_CS_L0  OUT  = NC
  BL70  VSS_BL70  POWER  = GND
  BL71  MEB_PAR  OUT  = M_E_CPU0_SB_PAR
  BL72  VSS_BL72  POWER  = GND
  BL73  MAB1_CS_L0  OUT  = NC
  BL74  MAB_PAR  OUT  = M_A_CPU0_SB_PAR
  BL75  VSS_BL75  POWER  = GND
  BM2  MGB1_CS_L1  OUT  = NC
  BM3  VSS_BM3  POWER  = GND
  BM4  MGB0_CS_L0  OUT  = M_G_CPU0_SB_CS_N<0>
  BM5  VDDCR_SOC_BM5  POWER  = PVDDCR_SOC_P0
  BM6  MKB1_CS_L1  OUT  = NC
  BM7  MKB0_CS_L0  OUT  = M_K_CPU0_SB_CS_N<0>
  BM8  VSS_BM8  POWER  = GND
  BM9  MLB1_CS_L1  OUT  = NC
  BM10  VSS_BM10  POWER  = GND
  BM11  MLB0_CS_L0  OUT  = M_L_CPU0_SB_CS_N<0>
  BM12  VDD_11_S3_BM12  POWER  = PVDD11_S3_P0
  BM13  MHB1_CS_L1  OUT  = NC
  BM14  MHB0_CS_L0  OUT  = M_H_CPU0_SB_CS_N<0>
  BM15  VSS_BM15  POWER  = GND
  BM16  MJB1_CS_L1  OUT  = NC
  BM17  VSS_BM17  POWER  = GND
  BM18  MJB0_CS_L0  OUT  = M_J_CPU0_SB_CS_N<0>
  BM19  VDD_11_S3_BM19  POWER  = PVDD11_S3_P0
  BM20  MIB1_CS_L1  OUT  = NC
  BM21  MIB0_CS_L0  OUT  = M_I_CPU0_SB_CS_N<0>
  BM22  VDD_11_S3_BM22  POWER  = PVDD11_S3_P0
  BM23  VSS_BM23  POWER  = GND
  BM24  VDD_11_S3_BM24  POWER  = PVDD11_S3_P0
  BM25  VSS_BM25  POWER  = GND
  BM26  VDD_11_S3_BM26  POWER  = PVDD11_S3_P0
  BM27  VSS_BM27  POWER  = GND
  BM28  VDD_11_S3_BM28  POWER  = PVDD11_S3_P0
  BM29  VSS_BM29  POWER  = GND
  BM30  VDD_11_S3_BM30  POWER  = PVDD11_S3_P0
  BM31  VSS_BM31  POWER  = GND
  BM32  VDD_11_S3_BM32  POWER  = PVDD11_S3_P0
  BM33  VSS_BM33  POWER  = GND
  BM34  VDD_11_S3_BM34  POWER  = PVDD11_S3_P0
  BM35  VSS_BM35  POWER  = GND
  BM36  VDD_11_S3_BM36  POWER  = PVDD11_S3_P0
  BM37  VSS_BM37  POWER  = GND
  BM39  VDD_11_S3_BM39  POWER  = PVDD11_S3_P0
  BM40  VSS_BM40  POWER  = GND
  BM41  VDD_11_S3_BM41  POWER  = PVDD11_S3_P0
  BM42  VSS_BM42  POWER  = GND
  BM43  VDD_11_S3_BM43  POWER  = PVDD11_S3_P0
  BM44  VSS_BM44  POWER  = GND
  BM45  VDD_11_S3_BM45  POWER  = PVDD11_S3_P0
  BM46  VSS_BM46  POWER  = GND
  BM47  VDD_11_S3_BM47  POWER  = PVDD11_S3_P0
  BM48  VSS_BM48  POWER  = GND
  BM49  VDD_11_S3_BM49  POWER  = PVDD11_S3_P0
  BM50  VSS_BM50  POWER  = GND
  BM51  VDDIO_BM51  POWER  = PVDDIO_P0
  BM52  VSS_BM52  POWER  = GND
  BM53  VDDIO_BM53  POWER  = PVDDIO_P0
  BM54  VSS_BM54  POWER  = GND
  BM55  MCB0_CS_L0  OUT  = M_C_CPU0_SB_CS_N<0>
  BM56  MCB1_CS_L1  OUT  = NC
  BM57  VDDIO_BM57  POWER  = PVDDIO_P0
  BM58  MDB0_CS_L0  OUT  = M_D_CPU0_SB_CS_N<0>
  BM59  VSS_BM59  POWER  = GND
  BM60  MDB1_CS_L1  OUT  = NC
  BM61  VSS_BM61  POWER  = GND
  BM62  MBB0_CS_L0  OUT  = M_B_CPU0_SB_CS_N<0>
  BM63  MBB1_CS_L1  OUT  = NC
  BM64  VDDIO_BM64  POWER  = PVDDIO_P0
  BM65  MFB0_CS_L0  OUT  = M_F_CPU0_SB_CS_N<0>
  BM66  VSS_BM66  POWER  = GND
  BM67  MFB1_CS_L1  OUT  = NC
  BM68  VSS_BM68  POWER  = GND
  BM69  MEB0_CS_L0  OUT  = M_E_CPU0_SB_CS_N<0>
  BM70  MEB1_CS_L1  OUT  = NC
  BM71  VDDIO_BM71  POWER  = PVDDIO_P0
  BM72  MAB0_CS_L0  OUT  = M_A_CPU0_SB_CS_N<0>
  BM73  VSS_BM73  POWER  = GND
  BM74  MAB1_CS_L1  OUT  = NC
  BN1  VSS_BN1  POWER  = GND
  BN2  MGB0_CS_L1  OUT  = M_G_CPU0_SB_CS_N<1>
  BN3  MGA0_RSP_L  IN  = M_G_CPU0_SA_RSP<0>
  BN4  VSS_BN4  POWER  = GND
  BN5  MKB0_CS_L1  OUT  = M_K_CPU0_SB_CS_N<1>
  BN6  VSS_BN6  POWER  = GND
  BN7  MKA0_RSP_L  IN  = M_K_CPU0_SA_RSP<0>
  BN8  VSS_BN8  POWER  = GND
  BN9  MLB0_CS_L1  OUT  = M_L_CPU0_SB_CS_N<1>
  BN10  MLA0_RSP_L  IN  = M_L_CPU0_SA_RSP<0>
  BN11  VSS_BN11  POWER  = GND
  BN12  MHB0_CS_L1  OUT  = M_H_CPU0_SB_CS_N<1>
  BN13  VSS_BN13  POWER  = GND
  BN14  MHA0_RSP_L  IN  = M_H_CPU0_SA_RSP<0>
  BN15  VSS_BN15  POWER  = GND
  BN16  MJB0_CS_L1  OUT  = M_J_CPU0_SB_CS_N<1>
  BN17  MJA0_RSP_L  IN  = M_J_CPU0_SA_RSP<0>
  BN18  VSS_BN18  POWER  = GND
  BN19  MIB0_CS_L1  OUT  = M_I_CPU0_SB_CS_N<1>
  BN20  VSS_BN20  POWER  = GND
  BN21  MIA0_RSP_L  IN  = M_I_CPU0_SA_RSP<0>
  BN22  VSS_BN22  POWER  = GND
  BN23  VDDBT_RTC_G  POWER  = P1V5_BAT
  BN24  VSS_BN24  POWER  = GND
  BN25  VDD_11_S3_BN25  POWER  = PVDD11_S3_P0
  BN26  VSS_BN26  POWER  = GND
  BN27  VDDCR_CPU1_BN27  POWER  = PVDDCR_CPU1_P0
  BN28  VSS_BN28  POWER  = GND
  BN29  VDD_11_S3_BN29  POWER  = PVDD11_S3_P0
  BN30  VSS_BN30  POWER  = GND
  BN31  VDDCR_CPU1_BN31  POWER  = PVDDCR_CPU1_P0
  BN32  VSS_BN32  POWER  = GND
  BN33  VDD_11_S3_BN33  POWER  = PVDD11_S3_P0
  BN34  VSS_BN34  POWER  = GND
  BN35  VDDCR_CPU1_BN35  POWER  = PVDDCR_CPU1_P0
  BN36  VSS_BN36  POWER  = GND
  BN40  VDD_11_S3_BN40  POWER  = PVDD11_S3_P0
  BN41  VSS_BN41  POWER  = GND
  BN42  VDDCR_CPU1_BN42  POWER  = PVDDCR_CPU1_P0
  BN43  VSS_BN43  POWER  = GND
  BN44  VDD_11_S3_BN44  POWER  = PVDD11_S3_P0
  BN45  VSS_BN45  POWER  = GND
  BN46  VDDCR_CPU1_BN46  POWER  = PVDDCR_CPU1_P0
  BN47  VSS_BN47  POWER  = GND
  BN48  VDD_11_S3_BN48  POWER  = PVDD11_S3_P0
  BN49  VSS_BN49  POWER  = GND
  BN50  VDDCR_CPU1_BN50  POWER  = PVDDCR_CPU1_P0
  BN51  VSS_BN51  POWER  = GND
  BN52  VDD_33_S5_BN52  POWER  = PVDD_33_S5
  BN53  VSS_BN53  POWER  = GND
  BN54  VDDIO_BN54  POWER  = PVDDIO_P0
  BN55  MCA0_RSP_L  IN  = M_C_CPU0_SA_RSP<0>
  BN56  VSS_BN56  POWER  = GND
  BN57  MCB0_CS_L1  OUT  = M_C_CPU0_SB_CS_N<1>
  BN58  VSS_BN58  POWER  = GND
  BN59  MDA0_RSP_L  IN  = M_D_CPU0_SA_RSP<0>
  BN60  MDB0_CS_L1  OUT  = M_D_CPU0_SB_CS_N<1>
  BN61  VSS_BN61  POWER  = GND
  BN62  MBA0_RSP_L  IN  = M_B_CPU0_SA_RSP<0>
  BN63  VSS_BN63  POWER  = GND
  BN64  MBB0_CS_L1  OUT  = M_B_CPU0_SB_CS_N<1>
  BN65  VSS_BN65  POWER  = GND
  BN66  MFA0_RSP_L  IN  = M_F_CPU0_SA_RSP<0>
  BN67  MFB0_CS_L1  OUT  = M_F_CPU0_SB_CS_N<1>
  BN68  VSS_BN68  POWER  = GND
  BN69  MEA0_RSP_L  IN  = M_E_CPU0_SA_RSP<0>
  BN70  VSS_BN70  POWER  = GND
  BN71  MEB0_CS_L1  OUT  = M_E_CPU0_SB_CS_N<1>
  BN72  VSS_BN72  POWER  = GND
  BN73  MAA0_RSP_L  IN  = M_A_CPU0_SA_RSP<0>
  BN74  MAB0_CS_L1  OUT  = M_A_CPU0_SB_CS_N<1>
  BN75  VSS_BN75  POWER  = GND
  BP2  MGB0_RSP_L  IN  = M_G_CPU0_SB_RSP<0>
  BP3  VSS_BP3  POWER  = GND
  BP4  MGA1_RSP_L  IN  = NC
  BP5  VSS_BP5  POWER  = GND
  BP6  MKB0_RSP_L  IN  = M_K_CPU0_SB_RSP<0>
  BP7  MKA1_RSP_L  IN  = NC
  BP8  VSS_BP8  POWER  = GND
  BP9  MLB0_RSP_L  IN  = M_L_CPU0_SB_RSP<0>
  BP10  VSS_BP10  POWER  = GND
  BP11  MLA1_RSP_L  IN  = NC
  BP12  VSS_BP12  POWER  = GND
  BP13  MHB0_RSP_L  IN  = M_H_CPU0_SB_RSP<0>
  BP14  MHA1_RSP_L  IN  = NC
  BP15  VSS_BP15  POWER  = GND
  BP16  MJB0_RSP_L  IN  = M_J_CPU0_SB_RSP<0>
  BP17  VSS_BP17  POWER  = GND
  BP18  MJA1_RSP_L  IN  = NC
  BP19  VSS_BP19  POWER  = GND
  BP20  MIB0_RSP_L  IN  = M_I_CPU0_SB_RSP<0>
  BP21  MIA1_RSP_L  IN  = NC
  BP22  VDD_11_S3_BP22  POWER  = PVDD11_S3_P0
  BP23  VSS_BP23  POWER  = GND
  BP24  VDDCR_CPU1_BP24  POWER  = PVDDCR_CPU1_P0
  BP25  VSS_BP25  POWER  = GND
  BP26  VDDCR_CPU1_BP26  POWER  = PVDDCR_CPU1_P0
  BP27  VSS_BP27  POWER  = GND
  BP28  VDDCR_CPU1_BP28  POWER  = PVDDCR_CPU1_P0
  BP29  VSS_BP29  POWER  = GND
  BP30  VDDCR_CPU1_BP30  POWER  = PVDDCR_CPU1_P0
  BP31  VSS_BP31  POWER  = GND
  BP32  VDDCR_CPU1_BP32  POWER  = PVDDCR_CPU1_P0
  BP33  VSS_BP33  POWER  = GND
  BP34  VDDCR_CPU1_BP34  POWER  = PVDDCR_CPU1_P0
  BP35  VSS_BP35  POWER  = GND
  BP36  VDDCR_CPU1_BP36  POWER  = PVDDCR_CPU1_P0
  BP37  VSS_BP37  POWER  = GND
  BP39  VDDCR_CPU1_BP39  POWER  = PVDDCR_CPU1_P0
  BP40  VSS_BP40  POWER  = GND
  BP41  VDDCR_CPU1_BP41  POWER  = PVDDCR_CPU1_P0
  BP42  VSS_BP42  POWER  = GND
  BP43  VDDCR_CPU1_BP43  POWER  = PVDDCR_CPU1_P0
  BP44  VSS_BP44  POWER  = GND
  BP45  VDDCR_CPU1_BP45  POWER  = PVDDCR_CPU1_P0
  BP46  VSS_BP46  POWER  = GND
  BP47  VDDCR_CPU1_BP47  POWER  = PVDDCR_CPU1_P0
  BP48  VSS_BP48  POWER  = GND
  BP49  VDDCR_CPU1_BP49  POWER  = PVDDCR_CPU1_P0
  BP50  VSS_BP50  POWER  = GND
  BP51  VDD_33_S5_BP51  POWER  = PVDD_33_S5
  BP52  VSS_BP52  POWER  = GND
  BP53  VDD_33_S5_SENSE  POWER  = TP_VSENSE_PVDD33_S5_P0
  BP54  VSS_BP54  POWER  = GND
  BP55  MCA1_RSP_L  IN  = NC
  BP56  MCB0_RSP_L  IN  = M_C_CPU0_SB_RSP<0>
  BP57  VSS_BP57  POWER  = GND
  BP58  MDA1_RSP_L  IN  = NC
  BP59  VSS_BP59  POWER  = GND
  BP60  MDB0_RSP_L  IN  = M_D_CPU0_SB_RSP<0>
  BP61  VSS_BP61  POWER  = GND
  BP62  MBA1_RSP_L  IN  = NC
  BP63  MBB0_RSP_L  IN  = M_B_CPU0_SB_RSP<0>
  BP64  VSS_BP64  POWER  = GND
  BP65  MFA1_RSP_L  IN  = NC
  BP66  VSS_BP66  POWER  = GND
  BP67  MFB0_RSP_L  IN  = M_F_CPU0_SB_RSP<0>
  BP68  VSS_BP68  POWER  = GND
  BP69  MEA1_RSP_L  IN  = NC
  BP70  MEB0_RSP_L  IN  = M_E_CPU0_SB_RSP<0>
  BP71  VSS_BP71  POWER  = GND
  BP72  MAA1_RSP_L  IN  = NC
  BP73  VSS_BP73  POWER  = GND
  BP74  MAB0_RSP_L  IN  = M_A_CPU0_SB_RSP<0>
  BR1  VSS_BR1  POWER  = GND
  BR2  MGB1_RSP_L  IN  = NC
  BR3  VSS_BR3  POWER  = GND
  BR4  VDD_11_S3_BR4  POWER  = PVDD11_S3_P0
  BR5  MKB1_RSP_L  IN  = NC
  BR6  VSS_BR6  POWER  = GND
  BR7  VSS_BR7  POWER  = GND
  BR8  VSS_BR8  POWER  = GND
  BR9  MLB1_RSP_L  IN  = NC
  BR10  VSS_BR10  POWER  = GND
  BR11  VDD_11_S3_BR11  POWER  = PVDD11_S3_P0
  BR12  MHB1_RSP_L  IN  = NC
  BR13  VSS_BR13  POWER  = GND
  BR14  VSS_BR14  POWER  = GND
  BR15  VSS_BR15  POWER  = GND
  BR16  MJB1_RSP_L  IN  = NC
  BR17  VSS_BR17  POWER  = GND
  BR18  VDD_11_S3_BR18  POWER  = PVDD11_S3_P0
  BR19  MIB1_RSP_L  IN  = NC
  BR20  VSS_BR20  POWER  = GND
  BR21  VSS_BR21  POWER  = GND
  BR22  VSS_BR22  POWER  = GND
  BR23  VDDCR_CPU1_BR23  POWER  = PVDDCR_CPU1_P0
  BR24  VSS_BR24  POWER  = GND
  BR25  VDDCR_CPU1_BR25  POWER  = PVDDCR_CPU1_P0
  BR26  VSS_BR26  POWER  = GND
  BR27  VDDCR_CPU1_BR27  POWER  = PVDDCR_CPU1_P0
  BR28  VSS_BR28  POWER  = GND
  BR29  VDDCR_CPU1_BR29  POWER  = PVDDCR_CPU1_P0
  BR30  VSS_BR30  POWER  = GND
  BR31  VDDCR_CPU1_BR31  POWER  = PVDDCR_CPU1_P0
  BR32  VSS_BR32  POWER  = GND
  BR33  VDDCR_CPU1_BR33  POWER  = PVDDCR_CPU1_P0
  BR34  VSS_BR34  POWER  = GND
  BR35  VDDCR_CPU1_BR35  POWER  = PVDDCR_CPU1_P0
  BR36  VSS_BR36  POWER  = GND
  BR40  VDDCR_CPU1_BR40  POWER  = PVDDCR_CPU1_P0
  BR41  VSS_BR41  POWER  = GND
  BR42  VDDCR_CPU1_BR42  POWER  = PVDDCR_CPU1_P0
  BR43  VSS_BR43  POWER  = GND
  BR44  VDDCR_CPU1_BR44  POWER  = PVDDCR_CPU1_P0
  BR45  VSS_BR45  POWER  = GND
  BR46  VDDCR_CPU1_BR46  POWER  = PVDDCR_CPU1_P0
  BR47  VSS_BR47  POWER  = GND
  BR48  VDDCR_CPU1_BR48  POWER  = PVDDCR_CPU1_P0
  BR49  VSS_BR49  POWER  = GND
  BR50  VDDCR_CPU1_BR50  POWER  = PVDDCR_CPU1_P0
  BR51  VSS_BR51  POWER  = GND
  BR52  VDDCR_CPU1_BR52  POWER  = PVDDCR_CPU1_P0
  BR53  VDDIO_SENSE  POWER  = VSENSE_PVDDIO_P0_DP
  BR54  VSS_SENSE_B  POWER  = VSENSE_VSS_SENSE_B_P0
  BR55  VSS_BR55  POWER  = GND
  BR56  VSS_BR56  POWER  = GND
  BR57  MCB1_RSP_L  IN  = NC
